(kicad_pcb
	(version 20241229)
	(generator "pcbnew")
	(generator_version "9.0")
	(general
		(thickness 1.294)
		(legacy_teardrops no)
	)
	(paper "A3")
	(title_block
		(title "Kintex 410T devboard")
		(date "2024-04-03")
		(rev "1.1.2")
		(comment 9 "footprints 910-915 of 975")
	)
	(layers
		(0 "F.Cu" mixed)
		(4 "In1.Cu" power)
		(6 "In2.Cu" power)
		(8 "In3.Cu" mixed)
		(10 "In4.Cu" power)
		(12 "In5.Cu" mixed)
		(14 "In6.Cu" power)
		(16 "In7.Cu" mixed)
		(18 "In8.Cu" power)
		(2 "B.Cu" mixed)
		(9 "F.Adhes" user "F.Adhesive")
		(11 "B.Adhes" user "B.Adhesive")
		(13 "F.Paste" user)
		(15 "B.Paste" user)
		(5 "F.SilkS" user "F.Silkscreen")
		(7 "B.SilkS" user "B.Silkscreen")
		(1 "F.Mask" user)
		(3 "B.Mask" user)
		(17 "Dwgs.User" user "User.Drawings")
		(19 "Cmts.User" user "User.Comments")
		(21 "Eco1.User" user "User.Eco1")
		(23 "Eco2.User" user "User.Eco2")
		(25 "Edge.Cuts" user)
		(27 "Margin" user)
		(31 "F.CrtYd" user "F.Courtyard")
		(29 "B.CrtYd" user "B.Courtyard")
		(35 "F.Fab" user)
		(33 "B.Fab" user)
	)
	(footprint "antmicro-footprints:C_0201"
		(layer "B.Cu")
		(at 191.2 120.2 -45)
		(descr "Capacitor SMD 0201")
		(tags "capacitor SMD 0201")
		(property "Reference" "C86"
			(at -4.40174 -35.72657 315)
			(unlocked yes)
			(layer "B.SilkS")
			(effects
				(font
					(size 0.7 0.7)
					(thickness 0.15)
				)
				(justify left bottom mirror)
			)
		)
		(property "Value" "C_4u7_0201"
			(at 0 -1.399999 135)
			(layer "B.Fab")
			(effects
				(font
					(size 0.7 0.7)
					(thickness 0.15)
				)
				(justify left bottom mirror)
			)
		)
		(property "Description" "SMD Multilayer Ceramic Capacitor, 4.7 µF, 6.3 V, 0201 [0603 Metric], ± 20%, X5R, GRM Series"
			(at 0 0 315)
			(layer "F.Fab")
			(hide yes)
			(effects
				(font
					(size 1.27 1.27)
					(thickness 0.15)
				)
			)
		)
		(property "Author" "Antmicro"
			(at -28.993052 170.404582 0)
			(layer "B.Fab")
			(hide yes)
			(effects
				(font
					(size 1 1)
					(thickness 0.15)
				)
				(justify mirror)
			)
		)
		(property "Dielectric" ""
			(at -28.993052 170.404582 0)
			(layer "B.Fab")
			(hide yes)
			(effects
				(font
					(size 1 1)
					(thickness 0.15)
				)
				(justify mirror)
			)
		)
		(property "License" "Apache-2.0"
			(at -28.993052 170.404582 0)
			(layer "B.Fab")
			(hide yes)
			(effects
				(font
					(size 1 1)
					(thickness 0.15)
				)
				(justify mirror)
			)
		)
		(property "MPN" "GRM035R60J475ME15D"
			(at -28.993052 170.404582 0)
			(layer "B.Fab")
			(hide yes)
			(effects
				(font
					(size 1 1)
					(thickness 0.15)
				)
				(justify mirror)
			)
		)
		(property "Manufacturer" "Murata"
			(at -28.993052 170.404582 0)
			(layer "B.Fab")
			(hide yes)
			(effects
				(font
					(size 1 1)
					(thickness 0.15)
				)
				(justify mirror)
			)
		)
		(property "Val" "4u7"
			(at -28.993052 170.404582 0)
			(layer "B.Fab")
			(hide yes)
			(effects
				(font
					(size 1 1)
					(thickness 0.15)
				)
				(justify mirror)
			)
		)
		(property "Voltage" ""
			(at -28.993052 170.404582 0)
			(layer "B.Fab")
			(hide yes)
			(effects
				(font
					(size 1 1)
					(thickness 0.15)
				)
				(justify mirror)
			)
		)
		(sheetname "FPGA supply")
		(sheetfile "fpga-supply.kicad_sch")
		(attr smd)
		(fp_poly
			(pts
				(xy -0.7 0.35) (xy 0.7 0.35) (xy 0.7 -0.35) (xy -0.7 -0.35)
			)
			(stroke
				(width 0.05)
				(type default)
			)
			(fill no)
			(layer "B.CrtYd")
		)
		(fp_poly
			(pts
				(xy 0.3 -0.15) (xy -0.301 -0.15) (xy -0.301 0.149) (xy 0.3 0.149)
			)
			(stroke
				(width 0.15)
				(type solid)
			)
			(fill no)
			(layer "B.Fab")
		)
		(pad "" smd roundrect
			(at -0.349 0.002 315)
			(size 0.318 0.36)
			(layers "B.Paste")
			(roundrect_rratio 0.25)
		)
		(pad "" smd roundrect
			(at 0.341 0.002 315)
			(size 0.318 0.36)
			(layers "B.Paste")
			(roundrect_rratio 0.25)
		)
		(pad "1" smd roundrect
			(at -0.321 0.002 315)
			(size 0.46 0.4)
			(layers "B.Cu" "B.Mask")
			(roundrect_rratio 0.25)
			(net 1 "GND")
			(pintype "passive")
		)
		(pad "2" smd roundrect
			(at 0.32 0.002 315)
			(size 0.46 0.4)
			(layers "B.Cu" "B.Mask")
			(roundrect_rratio 0.25)
			(net 6 "+1V0_MGTAVCC")
			(pintype "passive")
		)
	)
	(footprint "antmicro-footprints:C_0402_1005Metric"
		(layer "B.Cu")
		(at 194.5 117 -90)
		(descr "Capacitor SMD 0402")
		(tags "capacitor SMD 0402")
		(property "Reference" "C99"
			(at -1.1 -1.225 90)
			(layer "B.SilkS")
			(effects
				(font
					(size 0.7 0.7)
					(thickness 0.15)
				)
				(justify left bottom mirror)
			)
		)
		(property "Value" "C_100n_0402"
			(at 0 -1.169 90)
			(layer "B.Fab")
			(effects
				(font
					(size 0.7 0.7)
					(thickness 0.15)
				)
				(justify left bottom mirror)
			)
		)
		(property "Description" "SMD Multilayer Ceramic Capacitor, 0.1 µF, 50 V, 0402 [1005 Metric], ± 10%, X5R, GRM Series"
			(at 0 0 270)
			(layer "F.Fab")
			(hide yes)
			(effects
				(font
					(size 1.27 1.27)
					(thickness 0.15)
				)
			)
		)
		(property "Author" "Antmicro"
			(at 77.5 311.5 0)
			(layer "B.Fab")
			(hide yes)
			(effects
				(font
					(size 1 1)
					(thickness 0.15)
				)
				(justify mirror)
			)
		)
		(property "Dielectric" "X5R"
			(at 77.5 311.5 0)
			(layer "B.Fab")
			(hide yes)
			(effects
				(font
					(size 1 1)
					(thickness 0.15)
				)
				(justify mirror)
			)
		)
		(property "License" "Apache-2.0"
			(at 77.5 311.5 0)
			(layer "B.Fab")
			(hide yes)
			(effects
				(font
					(size 1 1)
					(thickness 0.15)
				)
				(justify mirror)
			)
		)
		(property "MPN" "GRM155R61H104KE14D"
			(at 77.5 311.5 0)
			(layer "B.Fab")
			(hide yes)
			(effects
				(font
					(size 1 1)
					(thickness 0.15)
				)
				(justify mirror)
			)
		)
		(property "Manufacturer" "Murata"
			(at 77.5 311.5 0)
			(layer "B.Fab")
			(hide yes)
			(effects
				(font
					(size 1 1)
					(thickness 0.15)
				)
				(justify mirror)
			)
		)
		(property "Val" "100n"
			(at 77.5 311.5 0)
			(layer "B.Fab")
			(hide yes)
			(effects
				(font
					(size 1 1)
					(thickness 0.15)
				)
				(justify mirror)
			)
		)
		(property "Voltage" "50V"
			(at 77.5 311.5 0)
			(layer "B.Fab")
			(hide yes)
			(effects
				(font
					(size 1 1)
					(thickness 0.15)
				)
				(justify mirror)
			)
		)
		(sheetname "FPGA Bank 18 & 32")
		(sheetfile "fpga-bank-18-32.kicad_sch")
		(attr smd)
		(fp_rect
			(start -0.925 0.47)
			(end 0.925 -0.47)
			(stroke
				(width 0.05)
				(type default)
			)
			(fill no)
			(layer "B.CrtYd")
		)
		(fp_line
			(start -0.494 0.25)
			(end 0.504 0.25)
			(stroke
				(width 0.15)
				(type solid)
			)
			(layer "B.Fab")
		)
		(fp_line
			(start 0.504 0.25)
			(end 0.504 -0.248)
			(stroke
				(width 0.15)
				(type solid)
			)
			(layer "B.Fab")
		)
		(fp_line
			(start -0.494 -0.248)
			(end -0.494 0.25)
			(stroke
				(width 0.15)
				(type solid)
			)
			(layer "B.Fab")
		)
		(fp_line
			(start 0.504 -0.248)
			(end -0.494 -0.248)
			(stroke
				(width 0.15)
				(type solid)
			)
			(layer "B.Fab")
		)
		(pad "1" smd roundrect
			(at -0.48 0 270)
			(size 0.59 0.64)
			(layers "B.Cu" "B.Mask" "B.Paste")
			(roundrect_rratio 0.25)
			(net 1 "GND")
			(pintype "passive")
		)
		(pad "2" smd roundrect
			(at 0.48 0 270)
			(size 0.59 0.64)
			(layers "B.Cu" "B.Mask" "B.Paste")
			(roundrect_rratio 0.25)
			(net 24 "+3V3")
			(pintype "passive")
		)
	)
	(footprint "antmicro-footprints:R_0402_1005Metric"
		(layer "B.Cu")
		(at 258.4 91 -90)
		(descr "Resistor SMD 0402")
		(tags "resistor SMD 0402")
		(property "Reference" "R356"
			(at -1.3 0.45 90)
			(layer "B.SilkS")
			(effects
				(font
					(size 0.7 0.7)
					(thickness 0.15)
				)
				(justify left bottom mirror)
			)
		)
		(property "Value" "R_100k_0402"
			(at 0 -1.4 90)
			(layer "B.Fab")
			(effects
				(font
					(size 0.7 0.7)
					(thickness 0.15)
				)
				(justify left bottom mirror)
			)
		)
		(property "Description" "SMD Chip Resistor, 100 kohm, ± 1%, 62.5 mW, 0402 [1005 Metric], Thick Film, General Purpose"
			(at 0 0 270)
			(layer "F.Fab")
			(hide yes)
			(effects
				(font
					(size 1.27 1.27)
					(thickness 0.15)
				)
			)
		)
		(property "Author" "Antmicro"
			(at 167.4 349.4 0)
			(layer "B.Fab")
			(hide yes)
			(effects
				(font
					(size 1 1)
					(thickness 0.15)
				)
				(justify mirror)
			)
		)
		(property "License" "Apache-2.0"
			(at 167.4 349.4 0)
			(layer "B.Fab")
			(hide yes)
			(effects
				(font
					(size 1 1)
					(thickness 0.15)
				)
				(justify mirror)
			)
		)
		(property "MPN" "CR0402-FX-1003GLF"
			(at 167.4 349.4 0)
			(layer "B.Fab")
			(hide yes)
			(effects
				(font
					(size 1 1)
					(thickness 0.15)
				)
				(justify mirror)
			)
		)
		(property "Manufacturer" "Bourns"
			(at 167.4 349.4 0)
			(layer "B.Fab")
			(hide yes)
			(effects
				(font
					(size 1 1)
					(thickness 0.15)
				)
				(justify mirror)
			)
		)
		(property "Tolerance" "1%"
			(at 167.4 349.4 0)
			(layer "B.Fab")
			(hide yes)
			(effects
				(font
					(size 1 1)
					(thickness 0.15)
				)
				(justify mirror)
			)
		)
		(property "Val" "100k"
			(at 167.4 349.4 0)
			(layer "B.Fab")
			(hide yes)
			(effects
				(font
					(size 1 1)
					(thickness 0.15)
				)
				(justify mirror)
			)
		)
		(sheetname "User GPIO + LED + button + DIP switch")
		(sheetfile "user-gpio.kicad_sch")
		(attr smd)
		(fp_rect
			(start -0.925 0.47)
			(end 0.925 -0.47)
			(stroke
				(width 0.05)
				(type default)
			)
			(fill no)
			(layer "B.CrtYd")
		)
		(fp_rect
			(start -0.5 0.25)
			(end 0.5 -0.25)
			(stroke
				(width 0.15)
				(type solid)
			)
			(fill no)
			(layer "B.Fab")
		)
		(pad "1" smd roundrect
			(at -0.48 0 270)
			(size 0.59 0.64)
			(layers "B.Cu" "B.Mask" "B.Paste")
			(roundrect_rratio 0.25)
			(net 1302 "/USER_IO.LED_GREEN3")
			(pintype "passive")
		)
		(pad "2" smd roundrect
			(at 0.48 0 270)
			(size 0.59 0.64)
			(layers "B.Cu" "B.Mask" "B.Paste")
			(roundrect_rratio 0.25)
			(net 1 "GND")
			(pintype "passive")
		)
	)
	(footprint "antmicro-footprints:R_0402_1005Metric"
		(layer "B.Cu")
		(at 229 154.2)
		(descr "Resistor SMD 0402")
		(tags "resistor SMD 0402")
		(property "Reference" "R223"
			(at 3.65 0.375 180)
			(layer "B.SilkS")
			(effects
				(font
					(size 0.7 0.7)
					(thickness 0.15)
				)
				(justify left bottom mirror)
			)
		)
		(property "Value" "R_10k_0402"
			(at 0 -1.4 180)
			(layer "B.Fab")
			(effects
				(font
					(size 0.7 0.7)
					(thickness 0.15)
				)
				(justify left bottom mirror)
			)
		)
		(property "Description" "SMD Chip Resistor, 10 kohm, ± 1%, 62.5 mW, 0402 [1005 Metric], Thick Film, General Purpose"
			(at 0 0 0)
			(layer "F.Fab")
			(hide yes)
			(effects
				(font
					(size 1.27 1.27)
					(thickness 0.15)
				)
			)
		)
		(property "Author" "Antmicro"
			(at 0 0 0)
			(layer "B.Fab")
			(hide yes)
			(effects
				(font
					(size 1 1)
					(thickness 0.15)
				)
				(justify mirror)
			)
		)
		(property "DNP" "DNP"
			(at 0 0 0)
			(layer "B.Fab")
			(hide yes)
			(effects
				(font
					(size 1 1)
					(thickness 0.15)
				)
				(justify mirror)
			)
		)
		(property "License" "Apache-2.0"
			(at 0 0 0)
			(layer "B.Fab")
			(hide yes)
			(effects
				(font
					(size 1 1)
					(thickness 0.15)
				)
				(justify mirror)
			)
		)
		(property "MPN" "CR0402-FX-1002GLF"
			(at 0 0 0)
			(layer "B.Fab")
			(hide yes)
			(effects
				(font
					(size 1 1)
					(thickness 0.15)
				)
				(justify mirror)
			)
		)
		(property "Manufacturer" "Bourns"
			(at 0 0 0)
			(layer "B.Fab")
			(hide yes)
			(effects
				(font
					(size 1 1)
					(thickness 0.15)
				)
				(justify mirror)
			)
		)
		(property "Tolerance" "1%"
			(at 0 0 0)
			(layer "B.Fab")
			(hide yes)
			(effects
				(font
					(size 1 1)
					(thickness 0.15)
				)
				(justify mirror)
			)
		)
		(property "Val" "10k"
			(at 0 0 0)
			(layer "B.Fab")
			(hide yes)
			(effects
				(font
					(size 1 1)
					(thickness 0.15)
				)
				(justify mirror)
			)
		)
		(property "dnp" ""
			(at 0 0 0)
			(layer "B.Fab")
			(hide yes)
			(effects
				(font
					(size 1 1)
					(thickness 0.15)
				)
				(justify mirror)
			)
		)
		(property "exclude_from_bom" ""
			(at 0 0 0)
			(layer "B.Fab")
			(hide yes)
			(effects
				(font
					(size 1 1)
					(thickness 0.15)
				)
				(justify mirror)
			)
		)
		(sheetname "HDMI + Ethernet")
		(sheetfile "hdmi-ethernet.kicad_sch")
		(attr smd exclude_from_bom)
		(fp_rect
			(start -0.925 0.47)
			(end 0.925 -0.47)
			(stroke
				(width 0.05)
				(type default)
			)
			(fill no)
			(layer "B.CrtYd")
		)
		(fp_rect
			(start -0.5 0.25)
			(end 0.5 -0.25)
			(stroke
				(width 0.15)
				(type solid)
			)
			(fill no)
			(layer "B.Fab")
		)
		(pad "1" smd roundrect
			(at -0.48 0)
			(size 0.59 0.64)
			(layers "B.Cu" "B.Mask" "B.Paste")
			(roundrect_rratio 0.25)
			(net 847 "/HDMI + Ethernet/ETH_LED_LINK-")
			(pintype "passive")
		)
		(pad "2" smd roundrect
			(at 0.48 0)
			(size 0.59 0.64)
			(layers "B.Cu" "B.Mask" "B.Paste")
			(roundrect_rratio 0.25)
			(net 26 "+1V8")
			(pintype "passive")
		)
	)
	(footprint "antmicro-footprints:NetTie-2_SMD_Pad0.127mm"
		(layer "B.Cu")
		(at 253.701 148.4 -90)
		(descr "Net tie, 2 pin, 0.127mm  SMD pads")
		(tags "net tie")
		(property "Reference" "NT12"
			(at -0.128 1.345 90)
			(layer "B.SilkS")
			(hide yes)
			(effects
				(font
					(size 0.7 0.7)
					(thickness 0.15)
				)
				(justify left bottom mirror)
			)
		)
		(property "Value" "Net-Tie_2"
			(at 0 -1.199 90)
			(layer "B.Fab")
			(effects
				(font
					(size 0.7 0.7)
					(thickness 0.15)
				)
				(justify left bottom mirror)
			)
		)
		(property "Description" "Net tie, 2 pins"
			(at 0 0 270)
			(layer "F.Fab")
			(hide yes)
			(effects
				(font
					(size 1.27 1.27)
					(thickness 0.15)
				)
			)
		)
		(property "Author" "Antmicro"
			(at 105.301 402.101 0)
			(layer "B.Fab")
			(hide yes)
			(effects
				(font
					(size 1 1)
					(thickness 0.15)
				)
				(justify mirror)
			)
		)
		(property "License" "Apache-2.0"
			(at 105.301 402.101 0)
			(layer "B.Fab")
			(hide yes)
			(effects
				(font
					(size 1 1)
					(thickness 0.15)
				)
				(justify mirror)
			)
		)
		(property "MPN" ""
			(at 105.301 402.101 0)
			(layer "B.Fab")
			(hide yes)
			(effects
				(font
					(size 1 1)
					(thickness 0.15)
				)
				(justify mirror)
			)
		)
		(property "Manufacturer" ""
			(at 105.301 402.101 0)
			(layer "B.Fab")
			(hide yes)
			(effects
				(font
					(size 1 1)
					(thickness 0.15)
				)
				(justify mirror)
			)
		)
		(sheetname "FPGA Bank 14 & 15")
		(sheetfile "fpga-bank-14-15.kicad_sch")
		(attr exclude_from_pos_files)
		(net_tie_pad_groups "1, 2")
		(fp_poly
			(pts
				(xy -0.0635 0.0635) (xy 0.0625 0.0635) (xy 0.0625 -0.0635) (xy -0.0635 -0.0635)
			)
			(stroke
				(width 0)
				(type solid)
			)
			(fill yes)
			(layer "B.Cu")
		)
		(pad "1" smd roundrect
			(at -0.127 0 90)
			(size 0.127 0.127)
			(layers "B.Cu")
			(roundrect_rratio 0.5)
			(chamfer_ratio 0)
			(chamfer top_left bottom_left)
			(net 1297 "/USB_SPI.~{CS}")
			(pinfunction "1")
			(pintype "passive")
		)
		(pad "2" smd roundrect
			(at 0.126 0 270)
			(size 0.127 0.127)
			(layers "B.Cu")
			(roundrect_rratio 0.5)
			(chamfer_ratio 0)
			(chamfer top_left bottom_left)
			(net 1325 "/SUP_MCU.~{SCS}")
			(pinfunction "2")
			(pintype "passive")
		)
	)
	(footprint "antmicro-footprints:R_0402_1005Metric"
		(layer "B.Cu")
		(at 182.1 168.7125 -90)
		(descr "Resistor SMD 0402")
		(tags "resistor SMD 0402")
		(property "Reference" "R303"
			(at -3.6125 -0.375 90)
			(layer "B.SilkS")
			(effects
				(font
					(size 0.7 0.7)
					(thickness 0.15)
				)
				(justify left bottom mirror)
			)
		)
		(property "Value" "R_0R_0402"
			(at 0 -1.4 90)
			(layer "B.Fab")
			(effects
				(font
					(size 0.7 0.7)
					(thickness 0.15)
				)
				(justify left bottom mirror)
			)
		)
		(property "Description" "SMD Chip Resistor, Jumper, 0 ohm, 100 mW, 0402 [1005 Metric], Thick Film, General Purpose"
			(at 0 0 270)
			(layer "F.Fab")
			(hide yes)
			(effects
				(font
					(size 1.27 1.27)
					(thickness 0.15)
				)
			)
		)
		(property "Author" "Antmicro"
			(at 13.3875 350.8125 0)
			(layer "B.Fab")
			(hide yes)
			(effects
				(font
					(size 1 1)
					(thickness 0.15)
				)
				(justify mirror)
			)
		)
		(property "Current" "1A"
			(at 13.3875 350.8125 0)
			(layer "B.Fab")
			(hide yes)
			(effects
				(font
					(size 1 1)
					(thickness 0.15)
				)
				(justify mirror)
			)
		)
		(property "DNP" "DNP"
			(at 13.3875 350.8125 0)
			(layer "B.Fab")
			(hide yes)
			(effects
				(font
					(size 1 1)
					(thickness 0.15)
				)
				(justify mirror)
			)
		)
		(property "License" "Apache-2.0"
			(at 13.3875 350.8125 0)
			(layer "B.Fab")
			(hide yes)
			(effects
				(font
					(size 1 1)
					(thickness 0.15)
				)
				(justify mirror)
			)
		)
		(property "MPN" "ERJ2GE0R00X"
			(at 13.3875 350.8125 0)
			(layer "B.Fab")
			(hide yes)
			(effects
				(font
					(size 1 1)
					(thickness 0.15)
				)
				(justify mirror)
			)
		)
		(property "Manufacturer" "Panasonic"
			(at 13.3875 350.8125 0)
			(layer "B.Fab")
			(hide yes)
			(effects
				(font
					(size 1 1)
					(thickness 0.15)
				)
				(justify mirror)
			)
		)
		(property "Tolerance" ""
			(at 13.3875 350.8125 0)
			(layer "B.Fab")
			(hide yes)
			(effects
				(font
					(size 1 1)
					(thickness 0.15)
				)
				(justify mirror)
			)
		)
		(property "Val" "0R"
			(at 13.3875 350.8125 0)
			(layer "B.Fab")
			(hide yes)
			(effects
				(font
					(size 1 1)
					(thickness 0.15)
				)
				(justify mirror)
			)
		)
		(property "dnp" ""
			(at 13.3875 350.8125 0)
			(layer "B.Fab")
			(hide yes)
			(effects
				(font
					(size 1 1)
					(thickness 0.15)
				)
				(justify mirror)
			)
		)
		(property "exclude_from_bom" ""
			(at 13.3875 350.8125 0)
			(layer "B.Fab")
			(hide yes)
			(effects
				(font
					(size 1 1)
					(thickness 0.15)
				)
				(justify mirror)
			)
		)
		(sheetname "DC-DC Converters")
		(sheetfile "dc-dc.kicad_sch")
		(attr smd exclude_from_bom)
		(fp_rect
			(start -0.925 0.47)
			(end 0.925 -0.47)
			(stroke
				(width 0.05)
				(type default)
			)
			(fill no)
			(layer "B.CrtYd")
		)
		(fp_rect
			(start -0.5 0.25)
			(end 0.5 -0.25)
			(stroke
				(width 0.15)
				(type solid)
			)
			(fill no)
			(layer "B.Fab")
		)
		(pad "1" smd roundrect
			(at -0.48 0 270)
			(size 0.59 0.64)
			(layers "B.Cu" "B.Mask" "B.Paste")
			(roundrect_rratio 0.25)
			(net 1218 "/DC-DC Converters/SENSE_3V3_2_N")
			(pintype "passive")
		)
		(pad "2" smd roundrect
			(at 0.48 0 270)
			(size 0.59 0.64)
			(layers "B.Cu" "B.Mask" "B.Paste")
			(roundrect_rratio 0.25)
			(net 957 "/DC-DC Converters/FB6")
			(pintype "passive")
		)
	)
)
